# T6G (Grand Teton) — schematic netlist excerpt (pin names and nets, part order shuffled) for the footprints in the layout excerpt that follows; sources: Cadence DE-HDL packaged netlist, KiCad conversion of 04192023_DAF0TMB3IC0_F0TG_MB_C_brd_V02_OCP.brd

PC621_10  Q_CAP  0.1UF 25V 10% X7R  pkg 0402  page 223 : A = PVDDCR_CPU1_P1_VCCS ; B = GND
R1147  Q_RES  0 5% EMPTY  pkg 0402LF  page 142 : A = OCP_V3_2_AUX_PWR_EN_R2 ; B = FM_OCP_V3_2_AUX_PWR_R_EN

(kicad_pcb
	(version 20260206)
	(generator "pcbnew")
	(generator_version "10.0")
	(general
		(thickness 1.6)
		(legacy_teardrops no)
	)
	(paper "A4")
	(title_block
		(title "04192023_DAF0TMB3IC0_F0TG_MB_C_brd_V02_OCP.brd")
		(comment 1 "Grand Teton / footprints 1896-1897 of 8354")
	)
	(layers
		(0 "F.Cu" signal "TOP")
		(4 "In1.Cu" signal "GND")
		(6 "In2.Cu" signal "IN1")
		(8 "In3.Cu" signal "GND1")
		(10 "In4.Cu" signal "IN2")
		(12 "In5.Cu" signal "GND2")
		(14 "In6.Cu" signal "IN3")
		(16 "In7.Cu" signal "GND3")
		(18 "In8.Cu" signal "VCC")
		(20 "In9.Cu" signal "VCC1")
		(22 "In10.Cu" signal "GND4")
		(24 "In11.Cu" signal "IN4")
		(26 "In12.Cu" signal "GND5")
		(28 "In13.Cu" signal "IN5")
		(30 "In14.Cu" signal "GND6")
		(32 "In15.Cu" signal "IN6")
		(34 "In16.Cu" signal "GND7")
		(2 "B.Cu" signal "BOTTOM")
		(9 "F.Adhes" user "F.Adhesive")
		(11 "B.Adhes" user "B.Adhesive")
		(13 "F.Paste" user "Package Geometry/Pastemask Top")
		(15 "B.Paste" user "Package Geometry/Pastemask Bottom")
		(5 "F.SilkS" user "Ref Des/Silkscreen Top")
		(7 "B.SilkS" user "Ref Des/Silkscreen Bottom")
		(1 "F.Mask" user "Board Geometry/Soldermask Top")
		(3 "B.Mask" user "Board Geometry/Soldermask Bottom")
		(17 "Dwgs.User" user "User.Drawings")
		(19 "Cmts.User" user "User.Comments")
		(21 "Eco1.User" user "User.Eco1")
		(23 "Eco2.User" user "User.Eco2")
		(25 "Edge.Cuts" user "Board Geometry/Outline")
		(27 "Margin" user)
		(31 "F.CrtYd" user "Package Geometry/Place Bound Top")
		(29 "B.CrtYd" user "Package Geometry/Place Bound Bottom")
		(35 "F.Fab" user "Ref Des/Assembly Top")
		(33 "B.Fab" user "Ref Des/Assembly Bottom")
	)
	(footprint ""
		(layer "F.Cu")
		(at 25.90673 -351.578672 90)
		(property "Reference" "PC621_10"
			(at 0 0 90)
			(layer "F.SilkS")
			(hide yes)
			(effects
				(font
					(size 1.27 1.27)
				)
			)
		)
		(property "Value" ""
			(at 0 0 90)
			(layer "F.Fab")
			(effects
				(font
					(size 1.27 1.27)
				)
			)
		)
		(duplicate_pad_numbers_are_jumpers no)
		(fp_line
			(start 0.7874 -0.4064)
			(end 0.7874 0.4064)
			(stroke
				(width 0.1524)
				(type default)
			)
			(layer "F.SilkS")
		)
		(fp_line
			(start -0.7874 -0.4064)
			(end 0.7874 -0.4064)
			(stroke
				(width 0.1524)
				(type default)
			)
			(layer "F.SilkS")
		)
		(fp_line
			(start 0.7874 0.4064)
			(end -0.7874 0.4064)
			(stroke
				(width 0.1524)
				(type default)
			)
			(layer "F.SilkS")
		)
		(fp_line
			(start -0.7874 0.4064)
			(end -0.7874 -0.4064)
			(stroke
				(width 0.1524)
				(type default)
			)
			(layer "F.SilkS")
		)
		(fp_line
			(start -0.12065 -0.305054)
			(end -0.12065 -0.2794)
			(stroke
				(width 0.1)
				(type default)
			)
			(layer "F.Fab")
		)
		(fp_line
			(start -0.67945 -0.305054)
			(end -0.12065 -0.305054)
			(stroke
				(width 0.1)
				(type default)
			)
			(layer "F.Fab")
		)
		(fp_line
			(start 0.67945 -0.3048)
			(end 0.67945 0.3048)
			(stroke
				(width 0.1)
				(type default)
			)
			(layer "F.Fab")
		)
		(fp_line
			(start 0.12065 -0.3048)
			(end 0.67945 -0.3048)
			(stroke
				(width 0.1)
				(type default)
			)
			(layer "F.Fab")
		)
		(fp_line
			(start 0.12065 -0.2794)
			(end 0.12065 -0.3048)
			(stroke
				(width 0.1)
				(type default)
			)
			(layer "F.Fab")
		)
		(fp_line
			(start -0.12065 -0.2794)
			(end 0.12065 -0.2794)
			(stroke
				(width 0.1)
				(type default)
			)
			(layer "F.Fab")
		)
		(fp_line
			(start 0.120396 0.2794)
			(end -0.12065 0.2794)
			(stroke
				(width 0.1)
				(type default)
			)
			(layer "F.Fab")
		)
		(fp_line
			(start -0.12065 0.2794)
			(end -0.12065 0.3048)
			(stroke
				(width 0.1)
				(type default)
			)
			(layer "F.Fab")
		)
		(fp_line
			(start 0.67945 0.3048)
			(end 0.120396 0.3048)
			(stroke
				(width 0.1)
				(type default)
			)
			(layer "F.Fab")
		)
		(fp_line
			(start 0.120396 0.3048)
			(end 0.120396 0.2794)
			(stroke
				(width 0.1)
				(type default)
			)
			(layer "F.Fab")
		)
		(fp_line
			(start -0.12065 0.3048)
			(end -0.67945 0.3048)
			(stroke
				(width 0.1)
				(type default)
			)
			(layer "F.Fab")
		)
		(fp_line
			(start -0.67945 0.3048)
			(end -0.67945 -0.305054)
			(stroke
				(width 0.1)
				(type default)
			)
			(layer "F.Fab")
		)
		(pad "1" smd circle
			(at -0.40005 0 90)
			(size 0 0)
			(layers "F.Cu" "F.Mask" "F.Paste")
			(net "PVDDCR_CPU1_P1_VCCS")
		)
		(pad "2" smd circle
			(at 0.40005 0 90)
			(size 0 0)
			(layers "F.Cu" "F.Mask" "F.Paste")
			(net "GND")
		)
	)
	(footprint ""
		(layer "F.Cu")
		(at 68.961 -53.594 180)
		(property "Reference" "R1147"
			(at 0 0 180)
			(layer "F.SilkS")
			(hide yes)
			(effects
				(font
					(size 1.27 1.27)
				)
			)
		)
		(property "Value" ""
			(at 0 0 180)
			(layer "F.Fab")
			(effects
				(font
					(size 1.27 1.27)
				)
			)
		)
		(duplicate_pad_numbers_are_jumpers no)
		(fp_line
			(start 0.7874 0.4064)
			(end -0.7874 0.4064)
			(stroke
				(width 0.1524)
				(type default)
			)
			(layer "F.SilkS")
		)
		(fp_line
			(start 0.7874 -0.4064)
			(end 0.7874 0.4064)
			(stroke
				(width 0.1524)
				(type default)
			)
			(layer "F.SilkS")
		)
		(fp_line
			(start -0.7874 0.4064)
			(end -0.7874 -0.4064)
			(stroke
				(width 0.1524)
				(type default)
			)
			(layer "F.SilkS")
		)
		(fp_line
			(start -0.7874 -0.4064)
			(end 0.7874 -0.4064)
			(stroke
				(width 0.1524)
				(type default)
			)
			(layer "F.SilkS")
		)
		(fp_line
			(start 0.67945 0.3048)
			(end 0.120396 0.3048)
			(stroke
				(width 0.1)
				(type default)
			)
			(layer "F.Fab")
		)
		(fp_line
			(start 0.67945 -0.3048)
			(end 0.67945 0.3048)
			(stroke
				(width 0.1)
				(type default)
			)
			(layer "F.Fab")
		)
		(fp_line
			(start 0.12065 -0.2794)
			(end 0.12065 -0.3048)
			(stroke
				(width 0.1)
				(type default)
			)
			(layer "F.Fab")
		)
		(fp_line
			(start 0.12065 -0.3048)
			(end 0.67945 -0.3048)
			(stroke
				(width 0.1)
				(type default)
			)
			(layer "F.Fab")
		)
		(fp_line
			(start 0.120396 0.3048)
			(end 0.120396 0.2794)
			(stroke
				(width 0.1)
				(type default)
			)
			(layer "F.Fab")
		)
		(fp_line
			(start 0.120396 0.2794)
			(end -0.12065 0.2794)
			(stroke
				(width 0.1)
				(type default)
			)
			(layer "F.Fab")
		)
		(fp_line
			(start -0.12065 0.3048)
			(end -0.67945 0.3048)
			(stroke
				(width 0.1)
				(type default)
			)
			(layer "F.Fab")
		)
		(fp_line
			(start -0.12065 0.2794)
			(end -0.12065 0.3048)
			(stroke
				(width 0.1)
				(type default)
			)
			(layer "F.Fab")
		)
		(fp_line
			(start -0.12065 -0.2794)
			(end 0.12065 -0.2794)
			(stroke
				(width 0.1)
				(type default)
			)
			(layer "F.Fab")
		)
		(fp_line
			(start -0.12065 -0.305054)
			(end -0.12065 -0.2794)
			(stroke
				(width 0.1)
				(type default)
			)
			(layer "F.Fab")
		)
		(fp_line
			(start -0.67945 0.3048)
			(end -0.67945 -0.305054)
			(stroke
				(width 0.1)
				(type default)
			)
			(layer "F.Fab")
		)
		(fp_line
			(start -0.67945 -0.305054)
			(end -0.12065 -0.305054)
			(stroke
				(width 0.1)
				(type default)
			)
			(layer "F.Fab")
		)
		(pad "1" smd circle
			(at -0.40005 0 180)
			(size 0 0)
			(layers "F.Cu" "F.Mask" "F.Paste")
			(net "OCP_V3_2_AUX_PWR_EN_R2")
		)
		(pad "2" smd circle
			(at 0.40005 0 180)
			(size 0 0)
			(layers "F.Cu" "F.Mask" "F.Paste")
			(net "FM_OCP_V3_2_AUX_PWR_R_EN")
		)
	)
)
